(kicad_pcb
	(version 20260206)
	(generator "pcbnew")
	(generator_version "10.0")
	(general
		(thickness 1.6)
		(legacy_teardrops no)
	)
	(paper "A4")
	(title_block
		(title "peb — Lightning_PEB_BRD.brd")
		(comment 1 "Lightning (Wiwynn / Facebook NVMe JBOF) / footprint 1445 of 2563 (U1), pads 815-932 of 1311")
	)
	(layers
		(0 "F.Cu" signal "TOP")
		(4 "In1.Cu" signal "L2GND")
		(6 "In2.Cu" signal "L3")
		(8 "In3.Cu" signal "L4VCC")
		(10 "In4.Cu" signal "L5VCC")
		(12 "In5.Cu" signal "L6")
		(14 "In6.Cu" signal "L7GND")
		(2 "B.Cu" signal "BOTTOM")
		(9 "F.Adhes" user "F.Adhesive")
		(11 "B.Adhes" user "B.Adhesive")
		(13 "F.Paste" user "Package Geometry/Pastemask Top")
		(15 "B.Paste" user "Package Geometry/Pastemask Bottom")
		(5 "F.SilkS" user "Ref Des/Silkscreen Top")
		(7 "B.SilkS" user "Ref Des/Silkscreen Bottom")
		(1 "F.Mask" user "Board Geometry/Soldermask Top")
		(3 "B.Mask" user "Board Geometry/Soldermask Bottom")
		(17 "Dwgs.User" user "User.Drawings")
		(19 "Cmts.User" user "User.Comments")
		(21 "Eco1.User" user "User.Eco1")
		(23 "Eco2.User" user "User.Eco2")
		(25 "Edge.Cuts" user "Board Geometry/Outline")
		(27 "Margin" user)
		(31 "F.CrtYd" user "Package Geometry/Place Bound Top")
		(29 "B.CrtYd" user "Package Geometry/Place Bound Bottom")
		(35 "F.Fab" user "Ref Des/Assembly Top")
		(33 "B.Fab" user "Ref Des/Assembly Bottom")
	)
	(footprint ""
		(layer "F.Cu")
		(at 240.599976 -47.999904 -90)
		(property "Reference" "U1"
			(at 0 0 270)
			(layer "F.SilkS")
			(hide yes)
			(effects
				(font
					(size 1.27 1.27)
				)
			)
		)
		(property "Value" "PM8546A-FEIP-GP"
			(at -25.785064 -6.40334 270)
			(unlocked yes)
			(layer "F.Fab")
			(hide yes)
			(effects
				(font
					(size 1.016 1.016)
					(thickness 0.1524)
				)
			)
		)
		(property "Device Type" "BGA1311C37D5H134"
			(at -25.785064 -7.92734 270)
			(unlocked yes)
			(layer "F.Fab")
			(hide yes)
			(effects
				(font
					(size 1.016 1.016)
					(thickness 0.1524)
				)
			)
		)
		(duplicate_pad_numbers_are_jumpers no)
		(pad "G11" smd circle
			(at -7.999984 -11.999976 270)
			(size 0.4572 0.4572)
			(layers "F.Cu" "F.Mask" "F.Paste")
			(net "DUT_AVD_PCIE")
		)
		(pad "G12" smd circle
			(at -6.999986 -11.999976 270)
			(size 0.4572 0.4572)
			(layers "F.Cu" "F.Mask" "F.Paste")
			(net "DUT_AVD_PCIE")
		)
		(pad "G13" smd circle
			(at -5.999988 -11.999976 270)
			(size 0.4572 0.4572)
			(layers "F.Cu" "F.Mask" "F.Paste")
			(net "DUT_AVD_PCIE")
		)
		(pad "G14" smd circle
			(at -4.99999 -11.999976 270)
			(size 0.4572 0.4572)
			(layers "F.Cu" "F.Mask" "F.Paste")
			(net "DUT_AVD_PCIE")
		)
		(pad "G15" smd circle
			(at -3.999992 -11.999976 270)
			(size 0.4572 0.4572)
			(layers "F.Cu" "F.Mask" "F.Paste")
			(net "GND")
		)
		(pad "G16" smd circle
			(at -2.999994 -11.999976 270)
			(size 0.4572 0.4572)
			(layers "F.Cu" "F.Mask" "F.Paste")
			(net "DUT_AVD_PCIE")
		)
		(pad "G17" smd circle
			(at -1.999996 -11.999976 270)
			(size 0.4572 0.4572)
			(layers "F.Cu" "F.Mask" "F.Paste")
			(net "DUT_AVD_PCIE")
		)
		(pad "G18" smd circle
			(at -0.999998 -11.999976 270)
			(size 0.4572 0.4572)
			(layers "F.Cu" "F.Mask" "F.Paste")
			(net "DUT_AVD_PCIE")
		)
		(pad "G19" smd circle
			(at 0 -11.999976 270)
			(size 0.4572 0.4572)
			(layers "F.Cu" "F.Mask" "F.Paste")
			(net "DUT_AVD_PCIE")
		)
		(pad "G20" smd circle
			(at 0.999998 -11.999976 270)
			(size 0.4572 0.4572)
			(layers "F.Cu" "F.Mask" "F.Paste")
			(net "DUT_AVD_PCIE")
		)
		(pad "G21" smd circle
			(at 1.999996 -11.999976 270)
			(size 0.4572 0.4572)
			(layers "F.Cu" "F.Mask" "F.Paste")
			(net "DUT_AVD_PCIE")
		)
		(pad "G22" smd circle
			(at 2.999994 -11.999976 270)
			(size 0.4572 0.4572)
			(layers "F.Cu" "F.Mask" "F.Paste")
			(net "DUT_AVD_PCIE")
		)
		(pad "G23" smd circle
			(at 3.999992 -11.999976 270)
			(size 0.4572 0.4572)
			(layers "F.Cu" "F.Mask" "F.Paste")
			(net "DUT_AVD_PCIE")
		)
		(pad "G24" smd circle
			(at 4.99999 -11.999976 270)
			(size 0.4572 0.4572)
			(layers "F.Cu" "F.Mask" "F.Paste")
			(net "DUT_AVD_PCIE")
		)
		(pad "G25" smd circle
			(at 5.999988 -11.999976 270)
			(size 0.4572 0.4572)
			(layers "F.Cu" "F.Mask" "F.Paste")
			(net "DUT_AVD_PCIE")
		)
		(pad "G26" smd circle
			(at 6.999986 -11.999976 270)
			(size 0.4572 0.4572)
			(layers "F.Cu" "F.Mask" "F.Paste")
			(net "DUT_AVD_PCIE")
		)
		(pad "G27" smd circle
			(at 7.999984 -11.999976 270)
			(size 0.4572 0.4572)
			(layers "F.Cu" "F.Mask" "F.Paste")
			(net "DUT_AVD_PCIE")
		)
		(pad "G28" smd circle
			(at 8.999982 -11.999976 270)
			(size 0.4572 0.4572)
			(layers "F.Cu" "F.Mask" "F.Paste")
			(net "DUT_AVD_PCIE")
		)
		(pad "G29" smd circle
			(at 9.99998 -11.999976 270)
			(size 0.4572 0.4572)
			(layers "F.Cu" "F.Mask" "F.Paste")
			(net "DUT_AVD_PCIE")
		)
		(pad "G30" smd circle
			(at 10.999978 -11.999976 270)
			(size 0.4572 0.4572)
			(layers "F.Cu" "F.Mask" "F.Paste")
			(net "DUT_AVD_PCIE")
		)
		(pad "G31" smd circle
			(at 11.999976 -11.999976 270)
			(size 0.4572 0.4572)
			(layers "F.Cu" "F.Mask" "F.Paste")
			(net "DUT_AVD_PCIE")
		)
		(pad "G32" smd circle
			(at 12.999974 -11.999976 270)
			(size 0.4572 0.4572)
			(layers "F.Cu" "F.Mask" "F.Paste")
			(net "DUT_AVD_PCIE")
		)
		(pad "G33" smd circle
			(at 13.999972 -11.999976 270)
			(size 0.4572 0.4572)
			(layers "F.Cu" "F.Mask" "F.Paste")
			(net "DUT_AVD_PCIE")
		)
		(pad "G34" smd circle
			(at 14.99997 -11.999976 270)
			(size 0.4572 0.4572)
			(layers "F.Cu" "F.Mask" "F.Paste")
			(net "GND")
		)
		(pad "G35" smd circle
			(at 15.999968 -11.999976 270)
			(size 0.4572 0.4572)
			(layers "F.Cu" "F.Mask" "F.Paste")
			(net "PCIE_TX_CAP_P1")
		)
		(pad "G36" smd circle
			(at 16.999966 -11.999976 270)
			(size 0.4572 0.4572)
			(layers "F.Cu" "F.Mask" "F.Paste")
			(net "PCIE_TX_CAP_N1")
		)
		(pad "H1" smd circle
			(at -17.999964 -10.999978 270)
			(size 0.4572 0.4572)
			(layers "F.Cu" "F.Mask" "F.Paste")
			(net "PCIE_TX_CAP_N38")
		)
		(pad "H2" smd circle
			(at -16.999966 -10.999978 270)
			(size 0.4572 0.4572)
			(layers "F.Cu" "F.Mask" "F.Paste")
			(net "PCIE_TX_CAP_P38")
		)
		(pad "H3" smd circle
			(at -15.999968 -10.999978 270)
			(size 0.4572 0.4572)
			(layers "F.Cu" "F.Mask" "F.Paste")
			(net "GND")
		)
		(pad "H4" smd circle
			(at -14.99997 -10.999978 270)
			(size 0.4572 0.4572)
			(layers "F.Cu" "F.Mask" "F.Paste")
			(net "PCIE_RX_N38")
		)
		(pad "H5" smd circle
			(at -13.999972 -10.999978 270)
			(size 0.4572 0.4572)
			(layers "F.Cu" "F.Mask" "F.Paste")
			(net "PCIE_RX_P38")
		)
		(pad "H6" smd circle
			(at -12.999974 -10.999978 270)
			(size 0.4572 0.4572)
			(layers "F.Cu" "F.Mask" "F.Paste")
			(net "GND")
		)
		(pad "H7" smd circle
			(at -11.999976 -10.999978 270)
			(size 0.4572 0.4572)
			(layers "F.Cu" "F.Mask" "F.Paste")
			(net "DUT_AVD_PCIE")
		)
		(pad "H8" smd circle
			(at -10.999978 -10.999978 270)
			(size 0.4572 0.4572)
			(layers "F.Cu" "F.Mask" "F.Paste")
			(net "GND")
		)
		(pad "H9" smd circle
			(at -9.99998 -10.999978 270)
			(size 0.4572 0.4572)
			(layers "F.Cu" "F.Mask" "F.Paste")
			(net "GND")
		)
		(pad "H10" smd circle
			(at -8.999982 -10.999978 270)
			(size 0.4572 0.4572)
			(layers "F.Cu" "F.Mask" "F.Paste")
			(net "GND")
		)
		(pad "H11" smd circle
			(at -7.999984 -10.999978 270)
			(size 0.4572 0.4572)
			(layers "F.Cu" "F.Mask" "F.Paste")
			(net "GND")
		)
		(pad "H12" smd circle
			(at -6.999986 -10.999978 270)
			(size 0.4572 0.4572)
			(layers "F.Cu" "F.Mask" "F.Paste")
			(net "GND")
		)
		(pad "H13" smd circle
			(at -5.999988 -10.999978 270)
			(size 0.4572 0.4572)
			(layers "F.Cu" "F.Mask" "F.Paste")
			(net "GND")
		)
		(pad "H14" smd circle
			(at -4.99999 -10.999978 270)
			(size 0.4572 0.4572)
			(layers "F.Cu" "F.Mask" "F.Paste")
			(net "GND")
		)
		(pad "H15" smd circle
			(at -3.999992 -10.999978 270)
			(size 0.4572 0.4572)
			(layers "F.Cu" "F.Mask" "F.Paste")
			(net "GND")
		)
		(pad "H16" smd circle
			(at -2.999994 -10.999978 270)
			(size 0.4572 0.4572)
			(layers "F.Cu" "F.Mask" "F.Paste")
			(net "GND")
		)
		(pad "H17" smd circle
			(at -1.999996 -10.999978 270)
			(size 0.4572 0.4572)
			(layers "F.Cu" "F.Mask" "F.Paste")
			(net "GND")
		)
		(pad "H18" smd circle
			(at -0.999998 -10.999978 270)
			(size 0.4572 0.4572)
			(layers "F.Cu" "F.Mask" "F.Paste")
			(net "GND")
		)
		(pad "H19" smd circle
			(at 0 -10.999978 270)
			(size 0.4572 0.4572)
			(layers "F.Cu" "F.Mask" "F.Paste")
			(net "GND")
		)
		(pad "H20" smd circle
			(at 0.999998 -10.999978 270)
			(size 0.4572 0.4572)
			(layers "F.Cu" "F.Mask" "F.Paste")
			(net "DUT_AVD_PCIE")
		)
		(pad "H21" smd circle
			(at 1.999996 -10.999978 270)
			(size 0.4572 0.4572)
			(layers "F.Cu" "F.Mask" "F.Paste")
			(net "GND")
		)
		(pad "H22" smd circle
			(at 2.999994 -10.999978 270)
			(size 0.4572 0.4572)
			(layers "F.Cu" "F.Mask" "F.Paste")
			(net "GND")
		)
		(pad "H23" smd circle
			(at 3.999992 -10.999978 270)
			(size 0.4572 0.4572)
			(layers "F.Cu" "F.Mask" "F.Paste")
			(net "GND")
		)
		(pad "H24" smd circle
			(at 4.99999 -10.999978 270)
			(size 0.4572 0.4572)
			(layers "F.Cu" "F.Mask" "F.Paste")
			(net "GND")
		)
		(pad "H25" smd circle
			(at 5.999988 -10.999978 270)
			(size 0.4572 0.4572)
			(layers "F.Cu" "F.Mask" "F.Paste")
			(net "DUT_AVD_PCIE")
		)
		(pad "H26" smd circle
			(at 6.999986 -10.999978 270)
			(size 0.4572 0.4572)
			(layers "F.Cu" "F.Mask" "F.Paste")
			(net "GND")
		)
		(pad "H27" smd circle
			(at 7.999984 -10.999978 270)
			(size 0.4572 0.4572)
			(layers "F.Cu" "F.Mask" "F.Paste")
			(net "Net_2104")
		)
		(pad "H28" smd circle
			(at 8.999982 -10.999978 270)
			(size 0.4572 0.4572)
			(layers "F.Cu" "F.Mask" "F.Paste")
			(net "Net_2103")
		)
		(pad "H29" smd circle
			(at 9.99998 -10.999978 270)
			(size 0.4572 0.4572)
			(layers "F.Cu" "F.Mask" "F.Paste")
			(net "Net_2102")
		)
		(pad "H30" smd circle
			(at 10.999978 -10.999978 270)
			(size 0.4572 0.4572)
			(layers "F.Cu" "F.Mask" "F.Paste")
			(net "Net_2101")
		)
		(pad "H31" smd circle
			(at 11.999976 -10.999978 270)
			(size 0.4572 0.4572)
			(layers "F.Cu" "F.Mask" "F.Paste")
			(net "AVS_ENB_R")
		)
		(pad "H32" smd circle
			(at 12.999974 -10.999978 270)
			(size 0.4572 0.4572)
			(layers "F.Cu" "F.Mask" "F.Paste")
			(net "Net_2099")
		)
		(pad "H33" smd circle
			(at 13.999972 -10.999978 270)
			(size 0.4572 0.4572)
			(layers "F.Cu" "F.Mask" "F.Paste")
			(net "Net_2098")
		)
		(pad "H34" smd circle
			(at 14.99997 -10.999978 270)
			(size 0.4572 0.4572)
			(layers "F.Cu" "F.Mask" "F.Paste")
			(net "GND")
		)
		(pad "H35" smd circle
			(at 15.999968 -10.999978 270)
			(size 0.4572 0.4572)
			(layers "F.Cu" "F.Mask" "F.Paste")
			(net "GND")
		)
		(pad "H36" smd circle
			(at 16.999966 -10.999978 270)
			(size 0.4572 0.4572)
			(layers "F.Cu" "F.Mask" "F.Paste")
			(net "PCIE_TX_CAP_P0")
		)
		(pad "H37" smd circle
			(at 17.999964 -10.999978 270)
			(size 0.4572 0.4572)
			(layers "F.Cu" "F.Mask" "F.Paste")
			(net "PCIE_TX_CAP_N0")
		)
		(pad "J2" smd circle
			(at -16.999966 -9.99998 270)
			(size 0.4572 0.4572)
			(layers "F.Cu" "F.Mask" "F.Paste")
			(net "PCIE_TX_CAP_N39")
		)
		(pad "J3" smd circle
			(at -15.999968 -9.99998 270)
			(size 0.4572 0.4572)
			(layers "F.Cu" "F.Mask" "F.Paste")
			(net "PCIE_TX_CAP_P39")
		)
		(pad "J4" smd circle
			(at -14.99997 -9.99998 270)
			(size 0.4572 0.4572)
			(layers "F.Cu" "F.Mask" "F.Paste")
			(net "GND")
		)
		(pad "J5" smd circle
			(at -13.999972 -9.99998 270)
			(size 0.4572 0.4572)
			(layers "F.Cu" "F.Mask" "F.Paste")
			(net "PCIE_RX_N39")
		)
		(pad "J6" smd circle
			(at -12.999974 -9.99998 270)
			(size 0.4572 0.4572)
			(layers "F.Cu" "F.Mask" "F.Paste")
			(net "PCIE_RX_P39")
		)
		(pad "J7" smd circle
			(at -11.999976 -9.99998 270)
			(size 0.4572 0.4572)
			(layers "F.Cu" "F.Mask" "F.Paste")
			(net "DUT_AVD_PCIE")
		)
		(pad "J8" smd circle
			(at -10.999978 -9.99998 270)
			(size 0.4572 0.4572)
			(layers "F.Cu" "F.Mask" "F.Paste")
			(net "GND")
		)
		(pad "J9" smd circle
			(at -9.99998 -9.99998 270)
			(size 0.4572 0.4572)
			(layers "F.Cu" "F.Mask" "F.Paste")
			(net "GND")
		)
		(pad "J10" smd circle
			(at -8.999982 -9.99998 270)
			(size 0.4572 0.4572)
			(layers "F.Cu" "F.Mask" "F.Paste")
			(net "GND")
		)
		(pad "J11" smd circle
			(at -7.999984 -9.99998 270)
			(size 0.4572 0.4572)
			(layers "F.Cu" "F.Mask" "F.Paste")
			(net "GND")
		)
		(pad "J12" smd circle
			(at -6.999986 -9.99998 270)
			(size 0.4572 0.4572)
			(layers "F.Cu" "F.Mask" "F.Paste")
			(net "GND")
		)
		(pad "J13" smd circle
			(at -5.999988 -9.99998 270)
			(size 0.4572 0.4572)
			(layers "F.Cu" "F.Mask" "F.Paste")
			(net "GND")
		)
		(pad "J14" smd circle
			(at -4.99999 -9.99998 270)
			(size 0.4572 0.4572)
			(layers "F.Cu" "F.Mask" "F.Paste")
			(net "GND")
		)
		(pad "J15" smd circle
			(at -3.999992 -9.99998 270)
			(size 0.4572 0.4572)
			(layers "F.Cu" "F.Mask" "F.Paste")
			(net "GND")
		)
		(pad "J16" smd circle
			(at -2.999994 -9.99998 270)
			(size 0.4572 0.4572)
			(layers "F.Cu" "F.Mask" "F.Paste")
			(net "GND")
		)
		(pad "J17" smd circle
			(at -1.999996 -9.99998 270)
			(size 0.4572 0.4572)
			(layers "F.Cu" "F.Mask" "F.Paste")
			(net "GND")
		)
		(pad "J18" smd circle
			(at -0.999998 -9.99998 270)
			(size 0.4572 0.4572)
			(layers "F.Cu" "F.Mask" "F.Paste")
			(net "GND")
		)
		(pad "J19" smd circle
			(at 0 -9.99998 270)
			(size 0.4572 0.4572)
			(layers "F.Cu" "F.Mask" "F.Paste")
			(net "GND")
		)
		(pad "J20" smd circle
			(at 0.999998 -9.99998 270)
			(size 0.4572 0.4572)
			(layers "F.Cu" "F.Mask" "F.Paste")
			(net "DUT_AVD_PCIE")
		)
		(pad "J21" smd circle
			(at 1.999996 -9.99998 270)
			(size 0.4572 0.4572)
			(layers "F.Cu" "F.Mask" "F.Paste")
			(net "GND")
		)
		(pad "J22" smd circle
			(at 2.999994 -9.99998 270)
			(size 0.4572 0.4572)
			(layers "F.Cu" "F.Mask" "F.Paste")
			(net "GND")
		)
		(pad "J23" smd circle
			(at 3.999992 -9.99998 270)
			(size 0.4572 0.4572)
			(layers "F.Cu" "F.Mask" "F.Paste")
			(net "GND")
		)
		(pad "J24" smd circle
			(at 4.99999 -9.99998 270)
			(size 0.4572 0.4572)
			(layers "F.Cu" "F.Mask" "F.Paste")
			(net "GND")
		)
		(pad "J25" smd circle
			(at 5.999988 -9.99998 270)
			(size 0.4572 0.4572)
			(layers "F.Cu" "F.Mask" "F.Paste")
			(net "DUT_AVD_PCIE")
		)
		(pad "J26" smd circle
			(at 6.999986 -9.99998 270)
			(size 0.4572 0.4572)
			(layers "F.Cu" "F.Mask" "F.Paste")
			(net "GND")
		)
		(pad "J27" smd circle
			(at 7.999984 -9.99998 270)
			(size 0.4572 0.4572)
			(layers "F.Cu" "F.Mask" "F.Paste")
			(net "Net_2100")
		)
		(pad "J28" smd circle
			(at 8.999982 -9.99998 270)
			(size 0.4572 0.4572)
			(layers "F.Cu" "F.Mask" "F.Paste")
			(net "VSS_573")
		)
		(pad "J29" smd circle
			(at 9.99998 -9.99998 270)
			(size 0.4572 0.4572)
			(layers "F.Cu" "F.Mask" "F.Paste")
			(net "THERM_BASE")
		)
		(pad "J30" smd circle
			(at 10.999978 -9.99998 270)
			(size 0.4572 0.4572)
			(layers "F.Cu" "F.Mask" "F.Paste")
			(net "THERM_EMIT")
		)
		(pad "J31" smd circle
			(at 11.999976 -9.99998 270)
			(size 0.4572 0.4572)
			(layers "F.Cu" "F.Mask" "F.Paste")
			(net "TWI_SCL0")
		)
		(pad "J32" smd circle
			(at 12.999974 -9.99998 270)
			(size 0.4572 0.4572)
			(layers "F.Cu" "F.Mask" "F.Paste")
			(net "TWI_SDA0")
		)
		(pad "J33" smd circle
			(at 13.999972 -9.99998 270)
			(size 0.4572 0.4572)
			(layers "F.Cu" "F.Mask" "F.Paste")
			(net "TWI_SRST#0")
		)
		(pad "J34" smd circle
			(at 14.99997 -9.99998 270)
			(size 0.4572 0.4572)
			(layers "F.Cu" "F.Mask" "F.Paste")
			(net "GND")
		)
		(pad "J35" smd circle
			(at 15.999968 -9.99998 270)
			(size 0.4572 0.4572)
			(layers "F.Cu" "F.Mask" "F.Paste")
			(net "GND")
		)
		(pad "J36" smd circle
			(at 16.999966 -9.99998 270)
			(size 0.4572 0.4572)
			(layers "F.Cu" "F.Mask" "F.Paste")
			(net "GND")
		)
		(pad "J37" smd circle
			(at 17.999964 -9.99998 270)
			(size 0.4572 0.4572)
			(layers "F.Cu" "F.Mask" "F.Paste")
			(net "GND")
		)
		(pad "K1" smd circle
			(at -17.999964 -8.999982 270)
			(size 0.4572 0.4572)
			(layers "F.Cu" "F.Mask" "F.Paste")
			(net "GND")
		)
		(pad "K2" smd circle
			(at -16.999966 -8.999982 270)
			(size 0.4572 0.4572)
			(layers "F.Cu" "F.Mask" "F.Paste")
			(net "GND")
		)
		(pad "K3" smd circle
			(at -15.999968 -8.999982 270)
			(size 0.4572 0.4572)
			(layers "F.Cu" "F.Mask" "F.Paste")
			(net "GND")
		)
		(pad "K4" smd circle
			(at -14.99997 -8.999982 270)
			(size 0.4572 0.4572)
			(layers "F.Cu" "F.Mask" "F.Paste")
			(net "GND")
		)
		(pad "K5" smd circle
			(at -13.999972 -8.999982 270)
			(size 0.4572 0.4572)
			(layers "F.Cu" "F.Mask" "F.Paste")
			(net "GND")
		)
		(pad "K6" smd circle
			(at -12.999974 -8.999982 270)
			(size 0.4572 0.4572)
			(layers "F.Cu" "F.Mask" "F.Paste")
			(net "GND")
		)
		(pad "K7" smd circle
			(at -11.999976 -8.999982 270)
			(size 0.4572 0.4572)
			(layers "F.Cu" "F.Mask" "F.Paste")
			(net "DUT_AVD_PCIE")
		)
		(pad "K8" smd circle
			(at -10.999978 -8.999982 270)
			(size 0.4572 0.4572)
			(layers "F.Cu" "F.Mask" "F.Paste")
			(net "GND")
		)
		(pad "K9" smd circle
			(at -9.99998 -8.999982 270)
			(size 0.4572 0.4572)
			(layers "F.Cu" "F.Mask" "F.Paste")
			(net "GND")
		)
		(pad "K10" smd circle
			(at -8.999982 -8.999982 270)
			(size 0.4572 0.4572)
			(layers "F.Cu" "F.Mask" "F.Paste")
			(net "GND")
		)
		(pad "K11" smd circle
			(at -7.999984 -8.999982 270)
			(size 0.4572 0.4572)
			(layers "F.Cu" "F.Mask" "F.Paste")
			(net "GND")
		)
		(pad "K12" smd circle
			(at -6.999986 -8.999982 270)
			(size 0.4572 0.4572)
			(layers "F.Cu" "F.Mask" "F.Paste")
			(net "GND")
		)
		(pad "K13" smd circle
			(at -5.999988 -8.999982 270)
			(size 0.4572 0.4572)
			(layers "F.Cu" "F.Mask" "F.Paste")
			(net "GND")
		)
		(pad "K14" smd circle
			(at -4.99999 -8.999982 270)
			(size 0.4572 0.4572)
			(layers "F.Cu" "F.Mask" "F.Paste")
			(net "GND")
		)
		(pad "K15" smd circle
			(at -3.999992 -8.999982 270)
			(size 0.4572 0.4572)
			(layers "F.Cu" "F.Mask" "F.Paste")
			(net "GND")
		)
		(pad "K16" smd circle
			(at -2.999994 -8.999982 270)
			(size 0.4572 0.4572)
			(layers "F.Cu" "F.Mask" "F.Paste")
			(net "GND")
		)
		(pad "K17" smd circle
			(at -1.999996 -8.999982 270)
			(size 0.4572 0.4572)
			(layers "F.Cu" "F.Mask" "F.Paste")
			(net "GND")
		)
		(pad "K18" smd circle
			(at -0.999998 -8.999982 270)
			(size 0.4572 0.4572)
			(layers "F.Cu" "F.Mask" "F.Paste")
			(net "GND")
		)
		(pad "K19" smd circle
			(at 0 -8.999982 270)
			(size 0.4572 0.4572)
			(layers "F.Cu" "F.Mask" "F.Paste")
			(net "GND")
		)
	)
)
